(kicad_pcb
	(version 20260206)
	(generator "pcbnew")
	(generator_version "10.0")
	(general
		(thickness 1.6)
		(legacy_teardrops no)
	)
	(paper "A4")
	(title_block
		(title "timecard-production-celestica-r4006 — R4006-B0001-02_R01.brd")
		(comment 1 "Time Appliance Project (Time Card) / footprints 542-545 of 1113")
	)
	(layers
		(0 "F.Cu" signal "TOP")
		(4 "In1.Cu" signal "L02_GND1")
		(6 "In2.Cu" signal "L03_SIG1")
		(8 "In3.Cu" signal "L04_GND2")
		(10 "In4.Cu" signal "L05_VCC1")
		(12 "In5.Cu" signal "L06_VCC2")
		(14 "In6.Cu" signal "L07_GND3")
		(16 "In7.Cu" signal "L08_SIG2")
		(18 "In8.Cu" signal "L09_GND4")
		(2 "B.Cu" signal "BOTTOM")
		(9 "F.Adhes" user "F.Adhesive")
		(11 "B.Adhes" user "B.Adhesive")
		(13 "F.Paste" user "Package Geometry/Pastemask Top")
		(15 "B.Paste" user "Package Geometry/Pastemask Bottom")
		(5 "F.SilkS" user "Ref Des/Silkscreen Top")
		(7 "B.SilkS" user "Ref Des/Silkscreen Bottom")
		(1 "F.Mask" user "Board Geometry/Soldermask Top")
		(3 "B.Mask" user "Board Geometry/Soldermask Bottom")
		(17 "Dwgs.User" user "User.Drawings")
		(19 "Cmts.User" user "User.Comments")
		(21 "Eco1.User" user "User.Eco1")
		(23 "Eco2.User" user "User.Eco2")
		(25 "Edge.Cuts" user "Board Geometry/Outline")
		(27 "Margin" user)
		(31 "F.CrtYd" user "Package Geometry/Place Bound Top")
		(29 "B.CrtYd" user "Package Geometry/Place Bound Bottom")
		(35 "F.Fab" user "Ref Des/Assembly Top")
		(33 "B.Fab" user "Ref Des/Assembly Bottom")
	)
	(footprint ""
		(layer "F.Cu")
		(at 72.661018 -26.426922)
		(property "Reference" "MAC_PIN4"
			(at 2.921762 2.580132 0)
			(unlocked yes)
			(layer "F.SilkS")
			(effects
				(font
					(size 0.7874 0.5842)
					(thickness 0.1524)
				)
			)
		)
		(property "Value" ""
			(at 0 0 0)
			(layer "F.Fab")
			(effects
				(font
					(size 1.27 1.27)
				)
			)
		)
		(property "User Part Number" "PARTNUM*"
			(at 0 3.826764 0)
			(unlocked yes)
			(layer "Cmts.User")
			(hide yes)
			(effects
				(font
					(size 0.7874 0.5842)
					(thickness 0.1524)
				)
			)
		)
		(property "Device Type" "NUT-A200-00029-FB"
			(at 0 2.632964 0)
			(unlocked yes)
			(layer "F.Fab")
			(hide yes)
			(effects
				(font
					(size 0.7874 0.5842)
					(thickness 0.1524)
				)
			)
		)
		(duplicate_pad_numbers_are_jumpers no)
		(fp_circle
			(center 0 0)
			(end 1.524 0)
			(stroke
				(width 0.1)
				(type default)
			)
			(fill no)
			(layer "F.SilkS")
		)
		(fp_poly
			(pts
				(arc
					(start -1.260856 -0.1524)
					(mid -0.898049 -0.898049)
					(end -0.1524 -1.260856)
				)
				(arc
					(start -0.1524 -0.991616)
					(mid -0.709411 -0.709411)
					(end -0.991616 -0.1524)
				)
			)
			(stroke
				(width 0)
				(type default)
			)
			(fill yes)
			(layer "F.Paste")
		)
		(fp_poly
			(pts
				(arc
					(start -0.1524 1.260856)
					(mid -0.898049 0.898049)
					(end -1.260856 0.1524)
				)
				(arc
					(start -0.991616 0.1524)
					(mid -0.709411 0.709411)
					(end -0.1524 0.991616)
				)
			)
			(stroke
				(width 0)
				(type default)
			)
			(fill yes)
			(layer "F.Paste")
		)
		(fp_poly
			(pts
				(arc
					(start 0.1524 -1.260856)
					(mid 0.898049 -0.898049)
					(end 1.260856 -0.1524)
				)
				(arc
					(start 0.991616 -0.1524)
					(mid 0.709411 -0.709411)
					(end 0.1524 -0.991616)
				)
			)
			(stroke
				(width 0)
				(type default)
			)
			(fill yes)
			(layer "F.Paste")
		)
		(fp_poly
			(pts
				(arc
					(start 1.260856 0.1524)
					(mid 0.898049 0.898049)
					(end 0.1524 1.260856)
				)
				(arc
					(start 0.1524 0.991616)
					(mid 0.709411 0.709411)
					(end 0.991616 0.1524)
				)
			)
			(stroke
				(width 0)
				(type default)
			)
			(fill yes)
			(layer "F.Paste")
		)
		(fp_poly
			(pts
				(arc
					(start 6.35 0)
					(mid -6.35 0)
					(end 6.35 0)
				)
			)
			(stroke
				(width 0)
				(type default)
			)
			(fill no)
			(layer "B.CrtYd")
		)
		(fp_poly
			(pts
				(arc
					(start 1.778 0)
					(mid -1.778 0)
					(end 1.778 0)
				)
			)
			(stroke
				(width 0)
				(type default)
			)
			(fill no)
			(layer "F.CrtYd")
		)
		(fp_circle
			(center 0 0)
			(end 1.1684 0)
			(stroke
				(width 0.1)
				(type default)
			)
			(fill no)
			(layer "F.Fab")
		)
		(pad "1" thru_hole circle
			(at 0 0)
			(size 2.54 2.54)
			(drill 2.0066)
			(layers "*.Cu" "*.Mask")
			(remove_unused_layers no)
			(net "SG")
			(thermal_gap 0.0254)
			(padstack
				(mode front_inner_back)
				(layer "Inner"
					(shape circle)
					(size 2.54 2.54)
					(clearance 0.0254)
				)
				(layer "B.Cu"
					(shape circle)
					(size 2.54 2.54)
				)
			)
		)
	)
	(footprint ""
		(layer "F.Cu")
		(at 115.443 -72.263)
		(property "Reference" "R237"
			(at 3.429 0.16637 0)
			(unlocked yes)
			(layer "F.SilkS")
			(effects
				(font
					(size 0.7874 0.5842)
					(thickness 0.1524)
				)
			)
		)
		(property "Value" "VAL*"
			(at 0.02032 2.13233 0)
			(unlocked yes)
			(layer "F.Fab")
			(hide yes)
			(effects
				(font
					(size 0.7874 0.5842)
					(thickness 0.1524)
				)
			)
		)
		(property "Tolerance" "TOL*"
			(at 0.044704 3.05435 0)
			(unlocked yes)
			(layer "Cmts.User")
			(hide yes)
			(effects
				(font
					(size 0.7874 0.5842)
					(thickness 0.1524)
				)
			)
		)
		(property "User Part Number" "PARTNUM*"
			(at 0.02032 4.024884 0)
			(unlocked yes)
			(layer "Cmts.User")
			(hide yes)
			(effects
				(font
					(size 0.7874 0.5842)
					(thickness 0.1524)
				)
			)
		)
		(property "Device Type" "RESISTOR-G155-11002-01,10KOHM,A"
			(at 0.008382 1.210564 0)
			(unlocked yes)
			(layer "F.Fab")
			(hide yes)
			(effects
				(font
					(size 0.7874 0.5842)
					(thickness 0.1524)
				)
			)
		)
		(duplicate_pad_numbers_are_jumpers no)
		(fp_line
			(start -1.143 -0.5588)
			(end -1.143 0.5588)
			(stroke
				(width 0.1)
				(type default)
			)
			(layer "F.SilkS")
		)
		(fp_line
			(start -1.143 0.5588)
			(end 1.143 0.5588)
			(stroke
				(width 0.1)
				(type default)
			)
			(layer "F.SilkS")
		)
		(fp_line
			(start 1.143 -0.5588)
			(end -1.143 -0.5588)
			(stroke
				(width 0.1)
				(type default)
			)
			(layer "F.SilkS")
		)
		(fp_line
			(start 1.143 0.5588)
			(end 1.143 -0.5588)
			(stroke
				(width 0.1)
				(type default)
			)
			(layer "F.SilkS")
		)
		(fp_poly
			(pts
				(xy -1.143 0.5588) (xy 1.143 0.5588) (xy 1.143 -0.5588) (xy -1.143 -0.5588)
			)
			(stroke
				(width 0)
				(type default)
			)
			(fill no)
			(layer "F.CrtYd")
		)
		(fp_line
			(start -0.508 -0.3048)
			(end -0.508 0.3048)
			(stroke
				(width 0.1)
				(type default)
			)
			(layer "F.Fab")
		)
		(fp_line
			(start -0.508 0.3048)
			(end 0.508 0.3048)
			(stroke
				(width 0.1)
				(type default)
			)
			(layer "F.Fab")
		)
		(fp_line
			(start 0.508 -0.3048)
			(end -0.508 -0.3048)
			(stroke
				(width 0.1)
				(type default)
			)
			(layer "F.Fab")
		)
		(fp_line
			(start 0.508 0.3048)
			(end 0.508 -0.3048)
			(stroke
				(width 0.1)
				(type default)
			)
			(layer "F.Fab")
		)
		(pad "1" smd rect
			(at -0.5334 0)
			(size 0.7112 0.6096)
			(layers "F.Cu" "F.Mask" "F.Paste")
			(net "XP3R3V_FPGA_EN_R")
		)
		(pad "2" smd rect
			(at 0.5334 0)
			(size 0.7112 0.6096)
			(layers "F.Cu" "F.Mask" "F.Paste")
			(net "SG")
		)
		(zone
			(layer "F.Cu")
			(hatch none 0.5)
			(connect_pads
				(clearance 0)
			)
			(min_thickness 0.25)
			(keepout
				(tracks not_allowed)
				(vias allowed)
				(pads allowed)
				(copperpour not_allowed)
				(footprints allowed)
			)
			(placement
				(enabled no)
				(sheetname "")
			)
			(fill
				(thermal_gap 0.5)
				(thermal_bridge_width 0.5)
				(island_removal_mode 0)
			)
			(polygon
				(pts
					(xy 115.3668 -71.9582) (xy 115.5192 -71.9582) (xy 115.5192 -72.5678) (xy 115.3668 -72.5678)
				)
			)
		)
		(zone
			(layer "F.Cu")
			(hatch none 0.5)
			(connect_pads
				(clearance 0)
			)
			(min_thickness 0.25)
			(keepout
				(tracks allowed)
				(vias not_allowed)
				(pads allowed)
				(copperpour not_allowed)
				(footprints allowed)
			)
			(placement
				(enabled no)
				(sheetname "")
			)
			(fill
				(thermal_gap 0.5)
				(thermal_bridge_width 0.5)
				(island_removal_mode 0)
			)
			(polygon
				(pts
					(xy 115.3668 -71.9582) (xy 115.5192 -71.9582) (xy 115.5192 -72.5678) (xy 115.3668 -72.5678)
				)
			)
		)
	)
	(footprint ""
		(layer "F.Cu")
		(at 75.565 -14.590014)
		(property "Reference" "R57"
			(at 0.127 1.294384 0)
			(unlocked yes)
			(layer "F.SilkS")
			(effects
				(font
					(size 0.7874 0.5842)
					(thickness 0.1524)
				)
			)
		)
		(property "Value" "VAL*"
			(at 0.02032 2.13233 0)
			(unlocked yes)
			(layer "F.Fab")
			(hide yes)
			(effects
				(font
					(size 0.7874 0.5842)
					(thickness 0.1524)
				)
			)
		)
		(property "Tolerance" "TOL*"
			(at 0.044704 3.05435 0)
			(unlocked yes)
			(layer "Cmts.User")
			(hide yes)
			(effects
				(font
					(size 0.7874 0.5842)
					(thickness 0.1524)
				)
			)
		)
		(property "User Part Number" "PARTNUM*"
			(at 0.02032 4.024884 0)
			(unlocked yes)
			(layer "Cmts.User")
			(hide yes)
			(effects
				(font
					(size 0.7874 0.5842)
					(thickness 0.1524)
				)
			)
		)
		(property "Device Type" "RESISTOR-G155-133R0-01,33OHM,1%"
			(at 0.008382 1.210564 0)
			(unlocked yes)
			(layer "F.Fab")
			(hide yes)
			(effects
				(font
					(size 0.7874 0.5842)
					(thickness 0.1524)
				)
			)
		)
		(duplicate_pad_numbers_are_jumpers no)
		(fp_line
			(start -1.143 -0.5588)
			(end -1.143 0.5588)
			(stroke
				(width 0.1)
				(type default)
			)
			(layer "F.SilkS")
		)
		(fp_line
			(start -1.143 0.5588)
			(end 1.143 0.5588)
			(stroke
				(width 0.1)
				(type default)
			)
			(layer "F.SilkS")
		)
		(fp_line
			(start 1.143 -0.5588)
			(end -1.143 -0.5588)
			(stroke
				(width 0.1)
				(type default)
			)
			(layer "F.SilkS")
		)
		(fp_line
			(start 1.143 0.5588)
			(end 1.143 -0.5588)
			(stroke
				(width 0.1)
				(type default)
			)
			(layer "F.SilkS")
		)
		(fp_rect
			(start -1.143 0.5588)
			(end 1.143 -0.5588)
			(stroke
				(width 0)
				(type default)
			)
			(fill no)
			(layer "F.CrtYd")
		)
		(fp_line
			(start -0.508 -0.3048)
			(end -0.508 0.3048)
			(stroke
				(width 0.1)
				(type default)
			)
			(layer "F.Fab")
		)
		(fp_line
			(start -0.508 0.3048)
			(end 0.508 0.3048)
			(stroke
				(width 0.1)
				(type default)
			)
			(layer "F.Fab")
		)
		(fp_line
			(start 0.508 -0.3048)
			(end -0.508 -0.3048)
			(stroke
				(width 0.1)
				(type default)
			)
			(layer "F.Fab")
		)
		(fp_line
			(start 0.508 0.3048)
			(end 0.508 -0.3048)
			(stroke
				(width 0.1)
				(type default)
			)
			(layer "F.Fab")
		)
		(pad "1" smd rect
			(at -0.5334 0)
			(size 0.7112 0.6096)
			(layers "F.Cu" "F.Mask" "F.Paste")
			(net "BF_PCIE_PERST_N")
		)
		(pad "2" smd rect
			(at 0.5334 0)
			(size 0.7112 0.6096)
			(layers "F.Cu" "F.Mask" "F.Paste")
			(net "PCIE_PERST_N")
		)
		(zone
			(layer "F.Cu")
			(hatch none 0.5)
			(connect_pads
				(clearance 0)
			)
			(min_thickness 0.25)
			(keepout
				(tracks allowed)
				(vias not_allowed)
				(pads allowed)
				(copperpour not_allowed)
				(footprints allowed)
			)
			(placement
				(enabled no)
				(sheetname "")
			)
			(fill
				(thermal_gap 0.5)
				(thermal_bridge_width 0.5)
				(island_removal_mode 0)
			)
			(polygon
				(pts
					(xy 75.4888 -14.285214) (xy 75.6412 -14.285214) (xy 75.6412 -14.894814) (xy 75.4888 -14.894814)
				)
			)
		)
	)
	(footprint ""
		(layer "F.Cu")
		(at 90.7542 -106.6038)
		(property "Reference" "C76"
			(at 0.0508 -1.81483 0)
			(unlocked yes)
			(layer "F.SilkS")
			(effects
				(font
					(size 0.7874 0.5842)
					(thickness 0.1524)
				)
			)
		)
		(property "Value" "VAL*"
			(at 0.0762 2.067306 0)
			(unlocked yes)
			(layer "F.Fab")
			(hide yes)
			(effects
				(font
					(size 0.7874 0.5842)
					(thickness 0.1524)
				)
			)
		)
		(property "Tolerance" "TOL*"
			(at 0.0762 3.032506 0)
			(unlocked yes)
			(layer "Cmts.User")
			(hide yes)
			(effects
				(font
					(size 0.7874 0.5842)
					(thickness 0.1524)
				)
			)
		)
		(property "User Part Number" "PARTNUM*"
			(at 0.1016 4.023106 0)
			(unlocked yes)
			(layer "Cmts.User")
			(hide yes)
			(effects
				(font
					(size 0.7874 0.5842)
					(thickness 0.1524)
				)
			)
		)
		(property "Device Type" "CAPACITOR-G105-0B104-EK,0.1UF,A"
			(at 0.0508 1.127506 0)
			(unlocked yes)
			(layer "F.Fab")
			(hide yes)
			(effects
				(font
					(size 0.7874 0.5842)
					(thickness 0.1524)
				)
			)
		)
		(duplicate_pad_numbers_are_jumpers no)
		(fp_line
			(start -1.143 -0.5588)
			(end -1.143 0.5588)
			(stroke
				(width 0.1)
				(type default)
			)
			(layer "F.SilkS")
		)
		(fp_line
			(start -1.143 0.5588)
			(end 1.143 0.5588)
			(stroke
				(width 0.1)
				(type default)
			)
			(layer "F.SilkS")
		)
		(fp_line
			(start 1.143 -0.5588)
			(end -1.143 -0.5588)
			(stroke
				(width 0.1)
				(type default)
			)
			(layer "F.SilkS")
		)
		(fp_line
			(start 1.143 0.5588)
			(end 1.143 -0.5588)
			(stroke
				(width 0.1)
				(type default)
			)
			(layer "F.SilkS")
		)
		(fp_rect
			(start -1.143 0.5588)
			(end 1.143 -0.5588)
			(stroke
				(width 0)
				(type default)
			)
			(fill no)
			(layer "F.CrtYd")
		)
		(fp_line
			(start -0.508 -0.3048)
			(end -0.508 0.3048)
			(stroke
				(width 0.1)
				(type default)
			)
			(layer "F.Fab")
		)
		(fp_line
			(start -0.508 0.3048)
			(end 0.508 0.3048)
			(stroke
				(width 0.1)
				(type default)
			)
			(layer "F.Fab")
		)
		(fp_line
			(start 0.508 -0.3048)
			(end -0.508 -0.3048)
			(stroke
				(width 0.1)
				(type default)
			)
			(layer "F.Fab")
		)
		(fp_line
			(start 0.508 0.3048)
			(end 0.508 -0.3048)
			(stroke
				(width 0.1)
				(type default)
			)
			(layer "F.Fab")
		)
		(pad "1" smd rect
			(at -0.5334 0)
			(size 0.7112 0.6096)
			(layers "F.Cu" "F.Mask" "F.Paste")
			(net "XP12R0V")
		)
		(pad "2" smd rect
			(at 0.5334 0)
			(size 0.7112 0.6096)
			(layers "F.Cu" "F.Mask" "F.Paste")
			(net "SG")
		)
		(zone
			(layer "F.Cu")
			(hatch none 0.5)
			(connect_pads
				(clearance 0)
			)
			(min_thickness 0.25)
			(keepout
				(tracks allowed)
				(vias not_allowed)
				(pads allowed)
				(copperpour not_allowed)
				(footprints allowed)
			)
			(placement
				(enabled no)
				(sheetname "")
			)
			(fill
				(thermal_gap 0.5)
				(thermal_bridge_width 0.5)
				(island_removal_mode 0)
			)
			(polygon
				(pts
					(xy 90.678 -106.299) (xy 90.8304 -106.299) (xy 90.8304 -106.9086) (xy 90.678 -106.9086)
				)
			)
		)
	)
)
